(kicad_pcb
	(version 20260206)
	(generator "pcbnew")
	(generator_version "10.0")
	(general
		(thickness 1.6)
		(legacy_teardrops no)
	)
	(paper "A4")
	(title_block
		(title "12092022_DA0F0TMDCD0_F0T_Management_Board_D_brd_V3_OCP.brd")
		(comment 1 "Grand Teton / footprints 1190-1195 of 1440")
	)
	(layers
		(0 "F.Cu" signal "TOP")
		(4 "In1.Cu" signal "GND")
		(6 "In2.Cu" signal "IN1")
		(8 "In3.Cu" signal "GND1")
		(10 "In4.Cu" signal "IN2")
		(12 "In5.Cu" signal "VCC")
		(14 "In6.Cu" signal "VCC1")
		(16 "In7.Cu" signal "IN3")
		(18 "In8.Cu" signal "GND2")
		(20 "In9.Cu" signal "IN4")
		(22 "In10.Cu" signal "GND3")
		(2 "B.Cu" signal "BOTTOM")
		(9 "F.Adhes" user "F.Adhesive")
		(11 "B.Adhes" user "B.Adhesive")
		(13 "F.Paste" user "Package Geometry/Pastemask Top")
		(15 "B.Paste" user "Package Geometry/Pastemask Bottom")
		(5 "F.SilkS" user "Ref Des/Silkscreen Top")
		(7 "B.SilkS" user "Ref Des/Silkscreen Bottom")
		(1 "F.Mask" user "Board Geometry/Soldermask Top")
		(3 "B.Mask" user "Board Geometry/Soldermask Bottom")
		(17 "Dwgs.User" user "User.Drawings")
		(19 "Cmts.User" user "User.Comments")
		(21 "Eco1.User" user "User.Eco1")
		(23 "Eco2.User" user "User.Eco2")
		(25 "Edge.Cuts" user "Board Geometry/Outline")
		(27 "Margin" user)
		(31 "F.CrtYd" user "Package Geometry/Place Bound Top")
		(29 "B.CrtYd" user "Package Geometry/Place Bound Bottom")
		(35 "F.Fab" user "Ref Des/Assembly Top")
		(33 "B.Fab" user "Ref Des/Assembly Bottom")
	)
	(footprint ""
		(layer "B.Cu")
		(at 72.799194 -55.399686 90)
		(property "Reference" "C108"
			(at 0 0 90)
			(layer "B.SilkS")
			(hide yes)
			(effects
				(font
					(size 1.27 1.27)
				)
				(justify mirror)
			)
		)
		(property "Value" ""
			(at 0 0 90)
			(layer "B.Fab")
			(effects
				(font
					(size 1.27 1.27)
				)
				(justify mirror)
			)
		)
		(duplicate_pad_numbers_are_jumpers no)
		(fp_line
			(start 0.7874 -0.4064)
			(end -0.7874 -0.4064)
			(stroke
				(width 0.1524)
				(type default)
			)
			(layer "B.SilkS")
		)
		(fp_line
			(start -0.7874 -0.4064)
			(end -0.7874 0.4064)
			(stroke
				(width 0.1524)
				(type default)
			)
			(layer "B.SilkS")
		)
		(fp_line
			(start 0.7874 0.4064)
			(end 0.7874 -0.4064)
			(stroke
				(width 0.1524)
				(type default)
			)
			(layer "B.SilkS")
		)
		(fp_line
			(start -0.7874 0.4064)
			(end 0.7874 0.4064)
			(stroke
				(width 0.1524)
				(type default)
			)
			(layer "B.SilkS")
		)
		(fp_line
			(start 0.67945 -0.305054)
			(end 0.12065 -0.305054)
			(stroke
				(width 0.1)
				(type default)
			)
			(layer "B.Fab")
		)
		(fp_line
			(start 0.12065 -0.305054)
			(end 0.12065 -0.2794)
			(stroke
				(width 0.1)
				(type default)
			)
			(layer "B.Fab")
		)
		(fp_line
			(start -0.12065 -0.3048)
			(end -0.67945 -0.3048)
			(stroke
				(width 0.1)
				(type default)
			)
			(layer "B.Fab")
		)
		(fp_line
			(start -0.67945 -0.3048)
			(end -0.67945 0.3048)
			(stroke
				(width 0.1)
				(type default)
			)
			(layer "B.Fab")
		)
		(fp_line
			(start 0.12065 -0.2794)
			(end -0.12065 -0.2794)
			(stroke
				(width 0.1)
				(type default)
			)
			(layer "B.Fab")
		)
		(fp_line
			(start -0.12065 -0.2794)
			(end -0.12065 -0.3048)
			(stroke
				(width 0.1)
				(type default)
			)
			(layer "B.Fab")
		)
		(fp_line
			(start 0.12065 0.2794)
			(end 0.12065 0.3048)
			(stroke
				(width 0.1)
				(type default)
			)
			(layer "B.Fab")
		)
		(fp_line
			(start -0.120396 0.2794)
			(end 0.12065 0.2794)
			(stroke
				(width 0.1)
				(type default)
			)
			(layer "B.Fab")
		)
		(fp_line
			(start 0.67945 0.3048)
			(end 0.67945 -0.305054)
			(stroke
				(width 0.1)
				(type default)
			)
			(layer "B.Fab")
		)
		(fp_line
			(start 0.12065 0.3048)
			(end 0.67945 0.3048)
			(stroke
				(width 0.1)
				(type default)
			)
			(layer "B.Fab")
		)
		(fp_line
			(start -0.120396 0.3048)
			(end -0.120396 0.2794)
			(stroke
				(width 0.1)
				(type default)
			)
			(layer "B.Fab")
		)
		(fp_line
			(start -0.67945 0.3048)
			(end -0.120396 0.3048)
			(stroke
				(width 0.1)
				(type default)
			)
			(layer "B.Fab")
		)
		(pad "1" smd circle
			(at 0.40005 0 270)
			(size 0 0)
			(layers "B.Cu" "B.Mask" "B.Paste")
			(net "P1V0_AUX")
		)
		(pad "2" smd circle
			(at -0.40005 0 270)
			(size 0 0)
			(layers "B.Cu" "B.Mask" "B.Paste")
			(net "GND")
		)
	)
	(footprint ""
		(layer "B.Cu")
		(at 47.10938 -24.1173 -90)
		(property "Reference" "R670"
			(at 0 0 90)
			(layer "B.SilkS")
			(hide yes)
			(effects
				(font
					(size 1.27 1.27)
				)
				(justify mirror)
			)
		)
		(property "Value" ""
			(at 0 0 90)
			(layer "B.Fab")
			(effects
				(font
					(size 1.27 1.27)
				)
				(justify mirror)
			)
		)
		(duplicate_pad_numbers_are_jumpers no)
		(fp_line
			(start -0.7874 0.4064)
			(end 0.7874 0.4064)
			(stroke
				(width 0.1524)
				(type default)
			)
			(layer "B.SilkS")
		)
		(fp_line
			(start 0.7874 0.4064)
			(end 0.7874 -0.4064)
			(stroke
				(width 0.1524)
				(type default)
			)
			(layer "B.SilkS")
		)
		(fp_line
			(start -0.7874 -0.4064)
			(end -0.7874 0.4064)
			(stroke
				(width 0.1524)
				(type default)
			)
			(layer "B.SilkS")
		)
		(fp_line
			(start 0.7874 -0.4064)
			(end -0.7874 -0.4064)
			(stroke
				(width 0.1524)
				(type default)
			)
			(layer "B.SilkS")
		)
		(fp_line
			(start -0.67945 0.3048)
			(end -0.120396 0.3048)
			(stroke
				(width 0.1)
				(type default)
			)
			(layer "B.Fab")
		)
		(fp_line
			(start -0.120396 0.3048)
			(end -0.120396 0.2794)
			(stroke
				(width 0.1)
				(type default)
			)
			(layer "B.Fab")
		)
		(fp_line
			(start 0.12065 0.3048)
			(end 0.67945 0.3048)
			(stroke
				(width 0.1)
				(type default)
			)
			(layer "B.Fab")
		)
		(fp_line
			(start 0.67945 0.3048)
			(end 0.67945 -0.305054)
			(stroke
				(width 0.1)
				(type default)
			)
			(layer "B.Fab")
		)
		(fp_line
			(start -0.120396 0.2794)
			(end 0.12065 0.2794)
			(stroke
				(width 0.1)
				(type default)
			)
			(layer "B.Fab")
		)
		(fp_line
			(start 0.12065 0.2794)
			(end 0.12065 0.3048)
			(stroke
				(width 0.1)
				(type default)
			)
			(layer "B.Fab")
		)
		(fp_line
			(start -0.12065 -0.2794)
			(end -0.12065 -0.3048)
			(stroke
				(width 0.1)
				(type default)
			)
			(layer "B.Fab")
		)
		(fp_line
			(start 0.12065 -0.2794)
			(end -0.12065 -0.2794)
			(stroke
				(width 0.1)
				(type default)
			)
			(layer "B.Fab")
		)
		(fp_line
			(start -0.67945 -0.3048)
			(end -0.67945 0.3048)
			(stroke
				(width 0.1)
				(type default)
			)
			(layer "B.Fab")
		)
		(fp_line
			(start -0.12065 -0.3048)
			(end -0.67945 -0.3048)
			(stroke
				(width 0.1)
				(type default)
			)
			(layer "B.Fab")
		)
		(fp_line
			(start 0.12065 -0.305054)
			(end 0.12065 -0.2794)
			(stroke
				(width 0.1)
				(type default)
			)
			(layer "B.Fab")
		)
		(fp_line
			(start 0.67945 -0.305054)
			(end 0.12065 -0.305054)
			(stroke
				(width 0.1)
				(type default)
			)
			(layer "B.Fab")
		)
		(pad "1" smd circle
			(at 0.40005 0 90)
			(size 0 0)
			(layers "B.Cu" "B.Mask" "B.Paste")
			(net "DEBUG_PORT_PRSNT_BUF_R_EN")
		)
		(pad "2" smd circle
			(at -0.40005 0 90)
			(size 0 0)
			(layers "B.Cu" "B.Mask" "B.Paste")
			(net "DEBUG_PORT_PRSNT_BUF_EN")
		)
	)
	(footprint ""
		(layer "B.Cu")
		(at 61.3918 -24.257 90)
		(property "Reference" "R193"
			(at 0 0 90)
			(layer "B.SilkS")
			(hide yes)
			(effects
				(font
					(size 1.27 1.27)
				)
				(justify mirror)
			)
		)
		(property "Value" ""
			(at 0 0 90)
			(layer "B.Fab")
			(effects
				(font
					(size 1.27 1.27)
				)
				(justify mirror)
			)
		)
		(duplicate_pad_numbers_are_jumpers no)
		(fp_line
			(start 0.7874 -0.4064)
			(end -0.7874 -0.4064)
			(stroke
				(width 0.1524)
				(type default)
			)
			(layer "B.SilkS")
		)
		(fp_line
			(start -0.7874 -0.4064)
			(end -0.7874 0.4064)
			(stroke
				(width 0.1524)
				(type default)
			)
			(layer "B.SilkS")
		)
		(fp_line
			(start 0.7874 0.4064)
			(end 0.7874 -0.4064)
			(stroke
				(width 0.1524)
				(type default)
			)
			(layer "B.SilkS")
		)
		(fp_line
			(start -0.7874 0.4064)
			(end 0.7874 0.4064)
			(stroke
				(width 0.1524)
				(type default)
			)
			(layer "B.SilkS")
		)
		(fp_line
			(start 0.67945 -0.305054)
			(end 0.12065 -0.305054)
			(stroke
				(width 0.1)
				(type default)
			)
			(layer "B.Fab")
		)
		(fp_line
			(start 0.12065 -0.305054)
			(end 0.12065 -0.2794)
			(stroke
				(width 0.1)
				(type default)
			)
			(layer "B.Fab")
		)
		(fp_line
			(start -0.12065 -0.3048)
			(end -0.67945 -0.3048)
			(stroke
				(width 0.1)
				(type default)
			)
			(layer "B.Fab")
		)
		(fp_line
			(start -0.67945 -0.3048)
			(end -0.67945 0.3048)
			(stroke
				(width 0.1)
				(type default)
			)
			(layer "B.Fab")
		)
		(fp_line
			(start 0.12065 -0.2794)
			(end -0.12065 -0.2794)
			(stroke
				(width 0.1)
				(type default)
			)
			(layer "B.Fab")
		)
		(fp_line
			(start -0.12065 -0.2794)
			(end -0.12065 -0.3048)
			(stroke
				(width 0.1)
				(type default)
			)
			(layer "B.Fab")
		)
		(fp_line
			(start 0.12065 0.2794)
			(end 0.12065 0.3048)
			(stroke
				(width 0.1)
				(type default)
			)
			(layer "B.Fab")
		)
		(fp_line
			(start -0.120396 0.2794)
			(end 0.12065 0.2794)
			(stroke
				(width 0.1)
				(type default)
			)
			(layer "B.Fab")
		)
		(fp_line
			(start 0.67945 0.3048)
			(end 0.67945 -0.305054)
			(stroke
				(width 0.1)
				(type default)
			)
			(layer "B.Fab")
		)
		(fp_line
			(start 0.12065 0.3048)
			(end 0.67945 0.3048)
			(stroke
				(width 0.1)
				(type default)
			)
			(layer "B.Fab")
		)
		(fp_line
			(start -0.120396 0.3048)
			(end -0.120396 0.2794)
			(stroke
				(width 0.1)
				(type default)
			)
			(layer "B.Fab")
		)
		(fp_line
			(start -0.67945 0.3048)
			(end -0.120396 0.3048)
			(stroke
				(width 0.1)
				(type default)
			)
			(layer "B.Fab")
		)
		(pad "1" smd circle
			(at 0.40005 0 270)
			(size 0 0)
			(layers "B.Cu" "B.Mask" "B.Paste")
			(net "P3V3_AUX")
		)
		(pad "2" smd circle
			(at -0.40005 0 270)
			(size 0 0)
			(layers "B.Cu" "B.Mask" "B.Paste")
			(net "SPA_SIN_SW_DBG")
		)
	)
	(footprint ""
		(layer "B.Cu")
		(at 32.6644 -71.882 180)
		(property "Reference" "R628"
			(at 0 0 0)
			(layer "B.SilkS")
			(hide yes)
			(effects
				(font
					(size 1.27 1.27)
				)
				(justify mirror)
			)
		)
		(property "Value" ""
			(at 0 0 0)
			(layer "B.Fab")
			(effects
				(font
					(size 1.27 1.27)
				)
				(justify mirror)
			)
		)
		(duplicate_pad_numbers_are_jumpers no)
		(fp_line
			(start 0.7874 0.4064)
			(end 0.7874 -0.4064)
			(stroke
				(width 0.1524)
				(type default)
			)
			(layer "B.SilkS")
		)
		(fp_line
			(start 0.7874 -0.4064)
			(end -0.7874 -0.4064)
			(stroke
				(width 0.1524)
				(type default)
			)
			(layer "B.SilkS")
		)
		(fp_line
			(start -0.7874 0.4064)
			(end 0.7874 0.4064)
			(stroke
				(width 0.1524)
				(type default)
			)
			(layer "B.SilkS")
		)
		(fp_line
			(start -0.7874 -0.4064)
			(end -0.7874 0.4064)
			(stroke
				(width 0.1524)
				(type default)
			)
			(layer "B.SilkS")
		)
		(fp_line
			(start 0.67945 0.3048)
			(end 0.67945 -0.305054)
			(stroke
				(width 0.1)
				(type default)
			)
			(layer "B.Fab")
		)
		(fp_line
			(start 0.67945 -0.305054)
			(end 0.12065 -0.305054)
			(stroke
				(width 0.1)
				(type default)
			)
			(layer "B.Fab")
		)
		(fp_line
			(start 0.12065 0.3048)
			(end 0.67945 0.3048)
			(stroke
				(width 0.1)
				(type default)
			)
			(layer "B.Fab")
		)
		(fp_line
			(start 0.12065 0.2794)
			(end 0.12065 0.3048)
			(stroke
				(width 0.1)
				(type default)
			)
			(layer "B.Fab")
		)
		(fp_line
			(start 0.12065 -0.2794)
			(end -0.12065 -0.2794)
			(stroke
				(width 0.1)
				(type default)
			)
			(layer "B.Fab")
		)
		(fp_line
			(start 0.12065 -0.305054)
			(end 0.12065 -0.2794)
			(stroke
				(width 0.1)
				(type default)
			)
			(layer "B.Fab")
		)
		(fp_line
			(start -0.120396 0.3048)
			(end -0.120396 0.2794)
			(stroke
				(width 0.1)
				(type default)
			)
			(layer "B.Fab")
		)
		(fp_line
			(start -0.120396 0.2794)
			(end 0.12065 0.2794)
			(stroke
				(width 0.1)
				(type default)
			)
			(layer "B.Fab")
		)
		(fp_line
			(start -0.12065 -0.2794)
			(end -0.12065 -0.3048)
			(stroke
				(width 0.1)
				(type default)
			)
			(layer "B.Fab")
		)
		(fp_line
			(start -0.12065 -0.3048)
			(end -0.67945 -0.3048)
			(stroke
				(width 0.1)
				(type default)
			)
			(layer "B.Fab")
		)
		(fp_line
			(start -0.67945 0.3048)
			(end -0.120396 0.3048)
			(stroke
				(width 0.1)
				(type default)
			)
			(layer "B.Fab")
		)
		(fp_line
			(start -0.67945 -0.3048)
			(end -0.67945 0.3048)
			(stroke
				(width 0.1)
				(type default)
			)
			(layer "B.Fab")
		)
		(pad "1" smd circle
			(at 0.40005 0)
			(size 0 0)
			(layers "B.Cu" "B.Mask" "B.Paste")
			(net "SPA_SIN_SW_DBG")
		)
		(pad "2" smd circle
			(at -0.40005 0)
			(size 0 0)
			(layers "B.Cu" "B.Mask" "B.Paste")
			(net "SPA_SIN_SW_DBG_R")
		)
	)
	(footprint ""
		(layer "B.Cu")
		(at 25.060656 -97.5868 -90)
		(property "Reference" "C260"
			(at 0 0 90)
			(layer "B.SilkS")
			(hide yes)
			(effects
				(font
					(size 1.27 1.27)
				)
				(justify mirror)
			)
		)
		(property "Value" ""
			(at 0 0 90)
			(layer "B.Fab")
			(effects
				(font
					(size 1.27 1.27)
				)
				(justify mirror)
			)
		)
		(duplicate_pad_numbers_are_jumpers no)
		(fp_line
			(start -0.69215 0.2921)
			(end 0.69215 0.2921)
			(stroke
				(width 0.1524)
				(type default)
			)
			(layer "B.SilkS")
		)
		(fp_line
			(start 0.69215 0.2921)
			(end 0.69215 -0.2921)
			(stroke
				(width 0.1524)
				(type default)
			)
			(layer "B.SilkS")
		)
		(fp_line
			(start -0.69215 -0.2921)
			(end -0.69215 0.2921)
			(stroke
				(width 0.1524)
				(type default)
			)
			(layer "B.SilkS")
		)
		(fp_line
			(start 0.69215 -0.2921)
			(end -0.69215 -0.2921)
			(stroke
				(width 0.1524)
				(type default)
			)
			(layer "B.SilkS")
		)
		(fp_line
			(start -0.51435 0.2794)
			(end 0.51435 0.2794)
			(stroke
				(width 0.1)
				(type default)
			)
			(layer "B.Fab")
		)
		(fp_line
			(start 0.51435 0.2794)
			(end 0.51435 -0.2794)
			(stroke
				(width 0.1)
				(type default)
			)
			(layer "B.Fab")
		)
		(fp_line
			(start -0.51435 -0.2794)
			(end -0.51435 0.2794)
			(stroke
				(width 0.1)
				(type default)
			)
			(layer "B.Fab")
		)
		(fp_line
			(start 0.51435 -0.2794)
			(end -0.51435 -0.2794)
			(stroke
				(width 0.1)
				(type default)
			)
			(layer "B.Fab")
		)
		(pad "1" smd circle
			(at 0.40005 0 90)
			(size 0 0)
			(layers "B.Cu" "B.Mask" "B.Paste")
			(net "VCCIO2")
		)
		(pad "2" smd circle
			(at -0.40005 0 90)
			(size 0 0)
			(layers "B.Cu" "B.Mask" "B.Paste")
			(net "GND")
		)
		(zone
			(layer "B.Cu")
			(hatch none 0.5)
			(connect_pads
				(clearance 0)
			)
			(min_thickness 0.25)
			(keepout
				(tracks not_allowed)
				(vias allowed)
				(pads allowed)
				(copperpour not_allowed)
				(footprints allowed)
			)
			(placement
				(enabled no)
				(sheetname "")
			)
			(fill
				(thermal_gap 0.5)
				(thermal_bridge_width 0.5)
				(island_removal_mode 0)
			)
			(polygon
				(pts
					(xy 24.973026 -97.3963) (xy 24.91486 -97.48774) (xy 24.91486 -97.68713) (xy 24.973026 -97.7773)
					(xy 25.148286 -97.7773) (xy 25.206706 -97.68713) (xy 25.206706 -97.48774) (xy 25.14854 -97.3963)
				)
			)
		)
	)
	(footprint ""
		(layer "B.Cu")
		(at 83.16722 -40.490394)
		(property "Reference" "R340"
			(at 0 0 0)
			(layer "B.SilkS")
			(hide yes)
			(effects
				(font
					(size 1.27 1.27)
				)
				(justify mirror)
			)
		)
		(property "Value" ""
			(at 0 0 0)
			(layer "B.Fab")
			(effects
				(font
					(size 1.27 1.27)
				)
				(justify mirror)
			)
		)
		(duplicate_pad_numbers_are_jumpers no)
		(fp_line
			(start -0.7874 -0.4064)
			(end -0.7874 0.4064)
			(stroke
				(width 0.1524)
				(type default)
			)
			(layer "B.SilkS")
		)
		(fp_line
			(start -0.7874 0.4064)
			(end 0.7874 0.4064)
			(stroke
				(width 0.1524)
				(type default)
			)
			(layer "B.SilkS")
		)
		(fp_line
			(start 0.7874 -0.4064)
			(end -0.7874 -0.4064)
			(stroke
				(width 0.1524)
				(type default)
			)
			(layer "B.SilkS")
		)
		(fp_line
			(start 0.7874 0.4064)
			(end 0.7874 -0.4064)
			(stroke
				(width 0.1524)
				(type default)
			)
			(layer "B.SilkS")
		)
		(fp_line
			(start -0.67945 -0.3048)
			(end -0.67945 0.3048)
			(stroke
				(width 0.1)
				(type default)
			)
			(layer "B.Fab")
		)
		(fp_line
			(start -0.67945 0.3048)
			(end -0.120396 0.3048)
			(stroke
				(width 0.1)
				(type default)
			)
			(layer "B.Fab")
		)
		(fp_line
			(start -0.12065 -0.3048)
			(end -0.67945 -0.3048)
			(stroke
				(width 0.1)
				(type default)
			)
			(layer "B.Fab")
		)
		(fp_line
			(start -0.12065 -0.2794)
			(end -0.12065 -0.3048)
			(stroke
				(width 0.1)
				(type default)
			)
			(layer "B.Fab")
		)
		(fp_line
			(start -0.120396 0.2794)
			(end 0.12065 0.2794)
			(stroke
				(width 0.1)
				(type default)
			)
			(layer "B.Fab")
		)
		(fp_line
			(start -0.120396 0.3048)
			(end -0.120396 0.2794)
			(stroke
				(width 0.1)
				(type default)
			)
			(layer "B.Fab")
		)
		(fp_line
			(start 0.12065 -0.305054)
			(end 0.12065 -0.2794)
			(stroke
				(width 0.1)
				(type default)
			)
			(layer "B.Fab")
		)
		(fp_line
			(start 0.12065 -0.2794)
			(end -0.12065 -0.2794)
			(stroke
				(width 0.1)
				(type default)
			)
			(layer "B.Fab")
		)
		(fp_line
			(start 0.12065 0.2794)
			(end 0.12065 0.3048)
			(stroke
				(width 0.1)
				(type default)
			)
			(layer "B.Fab")
		)
		(fp_line
			(start 0.12065 0.3048)
			(end 0.67945 0.3048)
			(stroke
				(width 0.1)
				(type default)
			)
			(layer "B.Fab")
		)
		(fp_line
			(start 0.67945 -0.305054)
			(end 0.12065 -0.305054)
			(stroke
				(width 0.1)
				(type default)
			)
			(layer "B.Fab")
		)
		(fp_line
			(start 0.67945 0.3048)
			(end 0.67945 -0.305054)
			(stroke
				(width 0.1)
				(type default)
			)
			(layer "B.Fab")
		)
		(pad "1" smd circle
			(at 0.40005 0 180)
			(size 0 0)
			(layers "B.Cu" "B.Mask" "B.Paste")
			(net "GND")
		)
		(pad "2" smd circle
			(at -0.40005 0 180)
			(size 0 0)
			(layers "B.Cu" "B.Mask" "B.Paste")
			(net "M_BMC_DDR4_MWE_N")
		)
	)
)
